(kicad_pcb
	(version 20241229)
	(generator "pcbnew")
	(generator_version "9.0")
	(general
		(thickness 1.61)
		(legacy_teardrops no)
	)
	(paper "A3")
	(title_block
		(title "SO-DIMM DDR5 Tester")
		(date "2025-11-26")
		(rev "1.3.0")
		(comment 9 "footprints 613-619 of 627")
	)
	(layers
		(0 "F.Cu" signal)
		(4 "In1.Cu" power)
		(6 "In2.Cu" mixed)
		(8 "In3.Cu" power)
		(10 "In4.Cu" mixed)
		(12 "In5.Cu" power)
		(14 "In6.Cu" mixed)
		(16 "In7.Cu" power)
		(18 "In8.Cu" power)
		(20 "In9.Cu" mixed)
		(22 "In10.Cu" power)
		(2 "B.Cu" signal)
		(9 "F.Adhes" user "F.Adhesive")
		(11 "B.Adhes" user "B.Adhesive")
		(13 "F.Paste" user)
		(15 "B.Paste" user)
		(5 "F.SilkS" user "F.Silkscreen")
		(7 "B.SilkS" user "B.Silkscreen")
		(1 "F.Mask" user)
		(3 "B.Mask" user)
		(17 "Dwgs.User" user "User.Drawings")
		(19 "Cmts.User" user "User.Comments")
		(21 "Eco1.User" user "User.Eco1")
		(23 "Eco2.User" user "User.Eco2")
		(25 "Edge.Cuts" user)
		(27 "Margin" user)
		(31 "F.CrtYd" user "F.Courtyard")
		(29 "B.CrtYd" user "B.Courtyard")
		(35 "F.Fab" user)
		(33 "B.Fab" user)
	)
	(footprint "antmicro-footprints:TP_SMD_1mm"
		(layer "B.Cu")
		(at 186.4 193.15 180)
		(property "Reference" "TP35"
			(at 0 0.731898 0)
			(layer "B.SilkS")
			(hide yes)
			(effects
				(font
					(size 0.7 0.7)
					(thickness 0.15)
				)
				(justify left bottom mirror)
			)
		)
		(property "Value" "TP_1mm_SMD"
			(at 0 -1.4 0)
			(layer "B.Fab")
			(effects
				(font
					(size 0.7 0.7)
					(thickness 0.15)
				)
				(justify left bottom mirror)
			)
		)
		(property "MPN" ""
			(at 0 0 0)
			(unlocked yes)
			(layer "B.Fab")
			(hide yes)
			(effects
				(font
					(size 1 1)
					(thickness 0.15)
				)
				(justify mirror)
			)
		)
		(property "Manufacturer" ""
			(at 0 0 0)
			(unlocked yes)
			(layer "B.Fab")
			(hide yes)
			(effects
				(font
					(size 1 1)
					(thickness 0.15)
				)
				(justify mirror)
			)
		)
		(property "Author" "Antmicro"
			(at 0 0 0)
			(unlocked yes)
			(layer "B.Fab")
			(hide yes)
			(effects
				(font
					(size 1 1)
					(thickness 0.15)
				)
				(justify mirror)
			)
		)
		(property "License" "Apache-2.0"
			(at 0 0 0)
			(unlocked yes)
			(layer "B.Fab")
			(hide yes)
			(effects
				(font
					(size 1 1)
					(thickness 0.15)
				)
				(justify mirror)
			)
		)
		(sheetname "/Supply/")
		(sheetfile "supply.kicad_sch")
		(attr exclude_from_pos_files)
		(fp_circle
			(center 0 0)
			(end 0.6 0)
			(stroke
				(width 0.05)
				(type default)
			)
			(fill no)
			(layer "B.CrtYd")
		)
		(fp_text user "${REFERENCE}"
			(at -0.5 -2.8 0)
			(layer "B.Fab")
			(effects
				(font
					(size 0.7 0.7)
					(thickness 0.15)
				)
				(justify left bottom mirror)
			)
		)
		(fp_text user "Author: Antmicro"
			(at -0.5 -4 0)
			(layer "B.Fab")
			(effects
				(font
					(size 0.7 0.7)
					(thickness 0.15)
				)
				(justify left bottom mirror)
			)
		)
		(fp_text user "License: Apache-2.0"
			(at -0.5 -5.2 0)
			(layer "B.Fab")
			(effects
				(font
					(size 0.7 0.7)
					(thickness 0.15)
				)
				(justify left bottom mirror)
			)
		)
		(pad "1" smd circle
			(at 0 0 180)
			(size 1 1)
			(layers "B.Cu" "B.Mask")
			(net 226 "+1V2_MGTAVTT")
			(pinfunction "1")
			(pintype "passive")
		)
	)
	(footprint "antmicro-footprints:R_0402_1005Metric"
		(layer "B.Cu")
		(at 159.700501 181.676)
		(descr "Resistor SMD 0402")
		(tags "resistor SMD 0402")
		(property "Reference" "R14"
			(at -1.122484 0.772697 180)
			(layer "B.SilkS")
			(hide yes)
			(effects
				(font
					(size 0.7 0.7)
					(thickness 0.15)
				)
				(justify left bottom mirror)
			)
		)
		(property "Value" "R_10k_0402"
			(at -1.011843 -1.772047 180)
			(layer "B.Fab")
			(effects
				(font
					(size 0.7 0.7)
					(thickness 0.15)
				)
				(justify left bottom mirror)
			)
		)
		(property "Datasheet" "https://www.bourns.com/docs/product-datasheets/cr.pdf"
			(at 0 0 0)
			(layer "F.Fab")
			(hide yes)
			(effects
				(font
					(size 1.27 1.27)
					(thickness 0.15)
				)
			)
		)
		(property "Author" "Antmicro"
			(at 0 0 0)
			(layer "B.Fab")
			(hide yes)
			(effects
				(font
					(size 1 1)
					(thickness 0.15)
				)
				(justify mirror)
			)
		)
		(property "License" "Apache-2.0"
			(at 0 0 0)
			(layer "B.Fab")
			(hide yes)
			(effects
				(font
					(size 1 1)
					(thickness 0.15)
				)
				(justify mirror)
			)
		)
		(property "MPN" "CR0402-FX-1002GLF"
			(at 0 0 0)
			(layer "B.Fab")
			(hide yes)
			(effects
				(font
					(size 1 1)
					(thickness 0.15)
				)
				(justify mirror)
			)
		)
		(property "Manufacturer" "Bourns"
			(at 0 0 0)
			(layer "B.Fab")
			(hide yes)
			(effects
				(font
					(size 1 1)
					(thickness 0.15)
				)
				(justify mirror)
			)
		)
		(property "Tolerance" "1%"
			(at 0 0 0)
			(layer "B.Fab")
			(hide yes)
			(effects
				(font
					(size 1 1)
					(thickness 0.15)
				)
				(justify mirror)
			)
		)
		(property "Val" "10k"
			(at 0 0 0)
			(layer "B.Fab")
			(hide yes)
			(effects
				(font
					(size 1 1)
					(thickness 0.15)
				)
				(justify mirror)
			)
		)
		(sheetname "/FPGA Config/")
		(sheetfile "fpga-config.kicad_sch")
		(attr smd)
		(fp_rect
			(start -0.93 0.47)
			(end 0.93 -0.47)
			(stroke
				(width 0.05)
				(type solid)
			)
			(fill no)
			(layer "B.CrtYd")
		)
		(fp_rect
			(start -0.5 0.25)
			(end 0.5 -0.25)
			(stroke
				(width 0.15)
				(type solid)
			)
			(fill no)
			(layer "B.Fab")
		)
		(pad "1" smd roundrect
			(at -0.485 0)
			(size 0.59 0.64)
			(layers "B.Cu" "B.Mask" "B.Paste")
			(roundrect_rratio 0.25)
			(net 631 "/FPGA Config/MODE2")
			(pintype "passive")
		)
		(pad "2" smd roundrect
			(at 0.485 0)
			(size 0.59 0.64)
			(layers "B.Cu" "B.Mask" "B.Paste")
			(roundrect_rratio 0.25)
			(net 200 "+3V3")
			(pintype "passive")
		)
	)
	(footprint "antmicro-footprints:TP_SMD_1mm"
		(layer "B.Cu")
		(at 182.88 177.9 180)
		(property "Reference" "TP36"
			(at 0 0.731898 0)
			(layer "B.SilkS")
			(hide yes)
			(effects
				(font
					(size 0.7 0.7)
					(thickness 0.15)
				)
				(justify left bottom mirror)
			)
		)
		(property "Value" "TP_1mm_SMD"
			(at 0 -1.4 0)
			(layer "B.Fab")
			(effects
				(font
					(size 0.7 0.7)
					(thickness 0.15)
				)
				(justify left bottom mirror)
			)
		)
		(property "MPN" ""
			(at 0 0 0)
			(unlocked yes)
			(layer "B.Fab")
			(hide yes)
			(effects
				(font
					(size 1 1)
					(thickness 0.15)
				)
				(justify mirror)
			)
		)
		(property "Manufacturer" ""
			(at 0 0 0)
			(unlocked yes)
			(layer "B.Fab")
			(hide yes)
			(effects
				(font
					(size 1 1)
					(thickness 0.15)
				)
				(justify mirror)
			)
		)
		(property "Author" "Antmicro"
			(at 0 0 0)
			(unlocked yes)
			(layer "B.Fab")
			(hide yes)
			(effects
				(font
					(size 1 1)
					(thickness 0.15)
				)
				(justify mirror)
			)
		)
		(property "License" "Apache-2.0"
			(at 0 0 0)
			(unlocked yes)
			(layer "B.Fab")
			(hide yes)
			(effects
				(font
					(size 1 1)
					(thickness 0.15)
				)
				(justify mirror)
			)
		)
		(sheetname "/Supply/")
		(sheetfile "supply.kicad_sch")
		(attr exclude_from_pos_files)
		(fp_circle
			(center 0 0)
			(end 0.6 0)
			(stroke
				(width 0.05)
				(type default)
			)
			(fill no)
			(layer "B.CrtYd")
		)
		(fp_text user "Author: Antmicro"
			(at -0.5 -4 0)
			(layer "B.Fab")
			(effects
				(font
					(size 0.7 0.7)
					(thickness 0.15)
				)
				(justify left bottom mirror)
			)
		)
		(fp_text user "${REFERENCE}"
			(at -0.5 -2.8 0)
			(layer "B.Fab")
			(effects
				(font
					(size 0.7 0.7)
					(thickness 0.15)
				)
				(justify left bottom mirror)
			)
		)
		(fp_text user "License: Apache-2.0"
			(at -0.5 -5.2 0)
			(layer "B.Fab")
			(effects
				(font
					(size 0.7 0.7)
					(thickness 0.15)
				)
				(justify left bottom mirror)
			)
		)
		(pad "1" smd circle
			(at 0 0 180)
			(size 1 1)
			(layers "B.Cu" "B.Mask")
			(net 1 "GND")
			(pinfunction "1")
			(pintype "passive")
		)
	)
	(footprint "antmicro-footprints:C_0402_1005Metric"
		(layer "B.Cu")
		(at 134.600501 189.276)
		(descr "Capacitor SMD 0402")
		(tags "capacitor SMD 0402")
		(property "Reference" "C164"
			(at 0 0.699 180)
			(layer "B.SilkS")
			(hide yes)
			(effects
				(font
					(size 0.7 0.7)
					(thickness 0.15)
				)
				(justify left bottom mirror)
			)
		)
		(property "Value" "C_100n_0402"
			(at -1.022927 -2.155213 180)
			(layer "B.Fab")
			(effects
				(font
					(size 0.7 0.7)
					(thickness 0.15)
				)
				(justify left bottom mirror)
			)
		)
		(property "Datasheet" "https://www.murata.com/products/productdetail?partno=GRM155R61H104KE14%23"
			(at 0 0 0)
			(layer "F.Fab")
			(hide yes)
			(effects
				(font
					(size 1.27 1.27)
					(thickness 0.15)
				)
			)
		)
		(property "Author" "Antmicro"
			(at 0 0 0)
			(layer "B.Fab")
			(hide yes)
			(effects
				(font
					(size 1 1)
					(thickness 0.15)
				)
				(justify mirror)
			)
		)
		(property "Dielectric" "X5R"
			(at 0 0 0)
			(layer "B.Fab")
			(hide yes)
			(effects
				(font
					(size 1 1)
					(thickness 0.15)
				)
				(justify mirror)
			)
		)
		(property "License" "Apache-2.0"
			(at 0 0 0)
			(layer "B.Fab")
			(hide yes)
			(effects
				(font
					(size 1 1)
					(thickness 0.15)
				)
				(justify mirror)
			)
		)
		(property "MPN" "GRM155R61H104KE14D"
			(at 0 0 0)
			(layer "B.Fab")
			(hide yes)
			(effects
				(font
					(size 1 1)
					(thickness 0.15)
				)
				(justify mirror)
			)
		)
		(property "Manufacturer" "Murata"
			(at 0 0 0)
			(layer "B.Fab")
			(hide yes)
			(effects
				(font
					(size 1 1)
					(thickness 0.15)
				)
				(justify mirror)
			)
		)
		(property "Val" "100n"
			(at 0 0 0)
			(layer "B.Fab")
			(hide yes)
			(effects
				(font
					(size 1 1)
					(thickness 0.15)
				)
				(justify mirror)
			)
		)
		(property "Voltage" "50V"
			(at 0 0 0)
			(layer "B.Fab")
			(hide yes)
			(effects
				(font
					(size 1 1)
					(thickness 0.15)
				)
				(justify mirror)
			)
		)
		(sheetname "/FPGA bank 16/")
		(sheetfile "fpga-bank-16.kicad_sch")
		(attr smd)
		(fp_rect
			(start -0.9659 0.481258)
			(end 0.9649 -0.458742)
			(stroke
				(width 0.05)
				(type solid)
			)
			(fill no)
			(layer "B.CrtYd")
		)
		(fp_line
			(start -0.499 -0.248)
			(end -0.499 0.25)
			(stroke
				(width 0.15)
				(type solid)
			)
			(layer "B.Fab")
		)
		(fp_line
			(start -0.499 0.25)
			(end 0.499 0.25)
			(stroke
				(width 0.15)
				(type solid)
			)
			(layer "B.Fab")
		)
		(fp_line
			(start 0.499 -0.248)
			(end -0.499 -0.248)
			(stroke
				(width 0.15)
				(type solid)
			)
			(layer "B.Fab")
		)
		(fp_line
			(start 0.499 0.25)
			(end 0.499 -0.248)
			(stroke
				(width 0.15)
				(type solid)
			)
			(layer "B.Fab")
		)
		(pad "1" smd roundrect
			(at -0.484 0)
			(size 0.59 0.64)
			(layers "B.Cu" "B.Mask" "B.Paste")
			(roundrect_rratio 0.25)
			(net 200 "+3V3")
			(pintype "passive")
		)
		(pad "2" smd roundrect
			(at 0.484 0)
			(size 0.59 0.64)
			(layers "B.Cu" "B.Mask" "B.Paste")
			(roundrect_rratio 0.25)
			(net 1 "GND")
			(pintype "passive")
		)
	)
	(footprint "antmicro-footprints:C_0402_1005Metric"
		(layer "B.Cu")
		(at 146.375501 176.801 -90)
		(descr "Capacitor SMD 0402 (1005 Metric), square (rectangular) end terminal, IPC_7351 nominal, (Body size source: IPC-SM-782 page 76, https://www.pcb-3d.com/wordpress/wp-content/uploads/ipc-sm-782a_amendment_1_and_2.pdf)")
		(tags "capacitor 0402")
		(property "Reference" "C97"
			(at 0 1.17 90)
			(layer "B.SilkS")
			(hide yes)
			(effects
				(font
					(size 0.7 0.7)
					(thickness 0.15)
				)
				(justify left bottom mirror)
			)
		)
		(property "Value" "C_4u7_0402"
			(at 0 -1.169 90)
			(layer "B.Fab")
			(effects
				(font
					(size 0.7 0.7)
					(thickness 0.15)
				)
				(justify left bottom mirror)
			)
		)
		(property "Datasheet" "https://www.murata.com/products/productdetail?partno=GRM155R61A475MEAA%23"
			(at 0 0 270)
			(layer "F.Fab")
			(hide yes)
			(effects
				(font
					(size 1.27 1.27)
					(thickness 0.15)
				)
			)
		)
		(property "Author" "Antmicro"
			(at -30.425499 323.176501 0)
			(layer "B.Fab")
			(hide yes)
			(effects
				(font
					(size 1 1)
					(thickness 0.15)
				)
				(justify mirror)
			)
		)
		(property "Dielectric" ""
			(at -30.425499 323.176501 0)
			(layer "B.Fab")
			(hide yes)
			(effects
				(font
					(size 1 1)
					(thickness 0.15)
				)
				(justify mirror)
			)
		)
		(property "License" "Apache-2.0"
			(at -30.425499 323.176501 0)
			(layer "B.Fab")
			(hide yes)
			(effects
				(font
					(size 1 1)
					(thickness 0.15)
				)
				(justify mirror)
			)
		)
		(property "MPN" "GRM155R61A475MEAAD"
			(at -30.425499 323.176501 0)
			(layer "B.Fab")
			(hide yes)
			(effects
				(font
					(size 1 1)
					(thickness 0.15)
				)
				(justify mirror)
			)
		)
		(property "Manufacturer" "Murata"
			(at -30.425499 323.176501 0)
			(layer "B.Fab")
			(hide yes)
			(effects
				(font
					(size 1 1)
					(thickness 0.15)
				)
				(justify mirror)
			)
		)
		(property "Val" "4u7"
			(at -30.425499 323.176501 0)
			(layer "B.Fab")
			(hide yes)
			(effects
				(font
					(size 1 1)
					(thickness 0.15)
				)
				(justify mirror)
			)
		)
		(property "Voltage" ""
			(at -30.425499 323.176501 0)
			(layer "B.Fab")
			(hide yes)
			(effects
				(font
					(size 1 1)
					(thickness 0.15)
				)
				(justify mirror)
			)
		)
		(sheetname "/FPGA power/")
		(sheetfile "fpga-power.kicad_sch")
		(attr smd)
		(fp_rect
			(start -0.9656 0.4572)
			(end 0.9652 -0.4828)
			(stroke
				(width 0.05)
				(type solid)
			)
			(fill no)
			(layer "B.CrtYd")
		)
		(fp_line
			(start -0.5 0.25)
			(end 0.498 0.25)
			(stroke
				(width 0.15)
				(type solid)
			)
			(layer "B.Fab")
		)
		(fp_line
			(start 0.498 0.25)
			(end 0.498 -0.248)
			(stroke
				(width 0.15)
				(type solid)
			)
			(layer "B.Fab")
		)
		(fp_line
			(start -0.5 -0.248)
			(end -0.5 0.25)
			(stroke
				(width 0.15)
				(type solid)
			)
			(layer "B.Fab")
		)
		(fp_line
			(start 0.498 -0.248)
			(end -0.5 -0.248)
			(stroke
				(width 0.15)
				(type solid)
			)
			(layer "B.Fab")
		)
		(pad "1" smd roundrect
			(at -0.5 0 180)
			(size 0.6 0.6)
			(layers "B.Cu" "B.Mask" "B.Paste")
			(roundrect_rratio 0.25)
			(net 188 "+1V8")
			(pintype "passive")
		)
		(pad "2" smd roundrect
			(at 0.498 0 270)
			(size 0.6 0.6)
			(layers "B.Cu" "B.Mask" "B.Paste")
			(roundrect_rratio 0.25)
			(net 1 "GND")
			(pintype "passive")
		)
	)
	(footprint "antmicro-footprints:R_0402_1005Metric"
		(layer "B.Cu")
		(at 195.3 138.75 90)
		(descr "Resistor SMD 0402")
		(tags "resistor SMD 0402")
		(property "Reference" "R160"
			(at -1.122484 0.772697 270)
			(layer "B.SilkS")
			(hide yes)
			(effects
				(font
					(size 0.7 0.7)
					(thickness 0.15)
				)
				(justify left bottom mirror)
			)
		)
		(property "Value" "R_47k_0402"
			(at -1.011843 -1.772047 270)
			(layer "B.Fab")
			(effects
				(font
					(size 0.7 0.7)
					(thickness 0.15)
				)
				(justify left bottom mirror)
			)
		)
		(property "Datasheet" "https://www.bourns.com/docs/product-datasheets/cr.pdf"
			(at 0 0 90)
			(layer "F.Fab")
			(hide yes)
			(effects
				(font
					(size 1.27 1.27)
					(thickness 0.15)
				)
			)
		)
		(property "Author" "Antmicro"
			(at 334.05 -56.55 0)
			(layer "B.Fab")
			(hide yes)
			(effects
				(font
					(size 1 1)
					(thickness 0.15)
				)
				(justify mirror)
			)
		)
		(property "License" "Apache-2.0"
			(at 334.05 -56.55 0)
			(layer "B.Fab")
			(hide yes)
			(effects
				(font
					(size 1 1)
					(thickness 0.15)
				)
				(justify mirror)
			)
		)
		(property "MPN" "CR0402-FX-4702GLF"
			(at 334.05 -56.55 0)
			(layer "B.Fab")
			(hide yes)
			(effects
				(font
					(size 1 1)
					(thickness 0.15)
				)
				(justify mirror)
			)
		)
		(property "Manufacturer" "Bourns"
			(at 334.05 -56.55 0)
			(layer "B.Fab")
			(hide yes)
			(effects
				(font
					(size 1 1)
					(thickness 0.15)
				)
				(justify mirror)
			)
		)
		(property "Tolerance" "1%"
			(at 334.05 -56.55 0)
			(layer "B.Fab")
			(hide yes)
			(effects
				(font
					(size 1 1)
					(thickness 0.15)
				)
				(justify mirror)
			)
		)
		(property "Val" "47k"
			(at 334.05 -56.55 0)
			(layer "B.Fab")
			(hide yes)
			(effects
				(font
					(size 1 1)
					(thickness 0.15)
				)
				(justify mirror)
			)
		)
		(sheetname "/Supply/")
		(sheetfile "supply.kicad_sch")
		(attr smd)
		(fp_rect
			(start -0.93 0.47)
			(end 0.93 -0.47)
			(stroke
				(width 0.05)
				(type solid)
			)
			(fill no)
			(layer "B.CrtYd")
		)
		(fp_rect
			(start -0.5 0.25)
			(end 0.5 -0.25)
			(stroke
				(width 0.15)
				(type solid)
			)
			(fill no)
			(layer "B.Fab")
		)
		(pad "1" smd roundrect
			(at -0.485 0 90)
			(size 0.59 0.64)
			(layers "B.Cu" "B.Mask" "B.Paste")
			(roundrect_rratio 0.25)
			(net 207 "/Supply/~{PB_CTRL_INT}")
			(pintype "passive")
		)
		(pad "2" smd roundrect
			(at 0.485 0 90)
			(size 0.59 0.64)
			(layers "B.Cu" "B.Mask" "B.Paste")
			(roundrect_rratio 0.25)
			(net 186 "/Supply/PB_CTRL_OUT")
			(pintype "passive")
		)
	)
	(footprint "antmicro-footprints:TP_SMD_1mm"
		(layer "B.Cu")
		(at 89.5 182.85 180)
		(property "Reference" "TP46"
			(at -1.4 0.7 0)
			(layer "B.SilkS")
			(effects
				(font
					(size 0.7 0.7)
					(thickness 0.15)
				)
				(justify left bottom mirror)
			)
		)
		(property "Value" "TP_1mm_SMD"
			(at 0 -1.4 0)
			(layer "B.Fab")
			(effects
				(font
					(size 0.7 0.7)
					(thickness 0.15)
				)
				(justify left bottom mirror)
			)
		)
		(property "MPN" ""
			(at 0 0 0)
			(unlocked yes)
			(layer "B.Fab")
			(hide yes)
			(effects
				(font
					(size 1 1)
					(thickness 0.15)
				)
				(justify mirror)
			)
		)
		(property "Manufacturer" ""
			(at 0 0 0)
			(unlocked yes)
			(layer "B.Fab")
			(hide yes)
			(effects
				(font
					(size 1 1)
					(thickness 0.15)
				)
				(justify mirror)
			)
		)
		(property "Author" "Antmicro"
			(at 0 0 0)
			(unlocked yes)
			(layer "B.Fab")
			(hide yes)
			(effects
				(font
					(size 1 1)
					(thickness 0.15)
				)
				(justify mirror)
			)
		)
		(property "License" "Apache-2.0"
			(at 0 0 0)
			(unlocked yes)
			(layer "B.Fab")
			(hide yes)
			(effects
				(font
					(size 1 1)
					(thickness 0.15)
				)
				(justify mirror)
			)
		)
		(sheetname "/Debug FTDI/")
		(sheetfile "debug-ftdi.kicad_sch")
		(attr exclude_from_pos_files)
		(fp_circle
			(center 0 0)
			(end 0.6 0)
			(stroke
				(width 0.05)
				(type default)
			)
			(fill no)
			(layer "B.CrtYd")
		)
		(fp_text user "Author: Antmicro"
			(at -0.5 -4 0)
			(layer "B.Fab")
			(effects
				(font
					(size 0.7 0.7)
					(thickness 0.15)
				)
				(justify left bottom mirror)
			)
		)
		(fp_text user "License: Apache-2.0"
			(at -0.5 -5.2 0)
			(layer "B.Fab")
			(effects
				(font
					(size 0.7 0.7)
					(thickness 0.15)
				)
				(justify left bottom mirror)
			)
		)
		(fp_text user "${REFERENCE}"
			(at -0.5 -2.8 0)
			(layer "B.Fab")
			(effects
				(font
					(size 0.7 0.7)
					(thickness 0.15)
				)
				(justify left bottom mirror)
			)
		)
		(pad "1" smd circle
			(at 0 0 180)
			(size 1 1)
			(layers "B.Cu" "B.Mask")
			(net 263 "FTDI_DIS")
			(pinfunction "1")
			(pintype "passive")
		)
	)
)
